(kicad_pcb
	(version 20260206)
	(generator "pcbnew")
	(generator_version "10.0")
	(general
		(thickness 1.6)
		(legacy_teardrops no)
	)
	(paper "A4")
	(title_block
		(title "03242023_DA0F0TMBIJ0_F0T_Motherboard_J_brd_V01_OCP.brd")
		(comment 1 "Grand Teton / footprints 5124-5129 of 6105")
	)
	(layers
		(0 "F.Cu" signal "TOP")
		(4 "In1.Cu" signal "GND")
		(6 "In2.Cu" signal "IN1")
		(8 "In3.Cu" signal "GND1")
		(10 "In4.Cu" signal "IN2")
		(12 "In5.Cu" signal "GND2")
		(14 "In6.Cu" signal "IN3")
		(16 "In7.Cu" signal "GND3")
		(18 "In8.Cu" signal "VCC")
		(20 "In9.Cu" signal "VCC1")
		(22 "In10.Cu" signal "GND4")
		(24 "In11.Cu" signal "IN4")
		(26 "In12.Cu" signal "GND5")
		(28 "In13.Cu" signal "IN5")
		(30 "In14.Cu" signal "GND6")
		(32 "In15.Cu" signal "IN6")
		(34 "In16.Cu" signal "GND7")
		(2 "B.Cu" signal "BOTTOM")
		(9 "F.Adhes" user "F.Adhesive")
		(11 "B.Adhes" user "B.Adhesive")
		(13 "F.Paste" user "Package Geometry/Pastemask Top")
		(15 "B.Paste" user "Package Geometry/Pastemask Bottom")
		(5 "F.SilkS" user "Ref Des/Silkscreen Top")
		(7 "B.SilkS" user "Ref Des/Silkscreen Bottom")
		(1 "F.Mask" user "Board Geometry/Soldermask Top")
		(3 "B.Mask" user "Board Geometry/Soldermask Bottom")
		(17 "Dwgs.User" user "User.Drawings")
		(19 "Cmts.User" user "User.Comments")
		(21 "Eco1.User" user "User.Eco1")
		(23 "Eco2.User" user "User.Eco2")
		(25 "Edge.Cuts" user "Board Geometry/Outline")
		(27 "Margin" user)
		(31 "F.CrtYd" user "Package Geometry/Place Bound Top")
		(29 "B.CrtYd" user "Package Geometry/Place Bound Bottom")
		(35 "F.Fab" user "Ref Des/Assembly Top")
		(33 "B.Fab" user "Ref Des/Assembly Bottom")
	)
	(footprint ""
		(layer "B.Cu")
		(at 385.46405 -188.70422 -90)
		(property "Reference" "R67"
			(at 0 0 90)
			(layer "B.SilkS")
			(hide yes)
			(effects
				(font
					(size 1.27 1.27)
				)
				(justify mirror)
			)
		)
		(property "Value" ""
			(at 0 0 90)
			(layer "B.Fab")
			(effects
				(font
					(size 1.27 1.27)
				)
				(justify mirror)
			)
		)
		(duplicate_pad_numbers_are_jumpers no)
		(fp_line
			(start -0.7874 0.4064)
			(end 0.7874 0.4064)
			(stroke
				(width 0.1524)
				(type default)
			)
			(layer "B.SilkS")
		)
		(fp_line
			(start 0.7874 0.4064)
			(end 0.7874 -0.4064)
			(stroke
				(width 0.1524)
				(type default)
			)
			(layer "B.SilkS")
		)
		(fp_line
			(start -0.7874 -0.4064)
			(end -0.7874 0.4064)
			(stroke
				(width 0.1524)
				(type default)
			)
			(layer "B.SilkS")
		)
		(fp_line
			(start 0.7874 -0.4064)
			(end -0.7874 -0.4064)
			(stroke
				(width 0.1524)
				(type default)
			)
			(layer "B.SilkS")
		)
		(fp_line
			(start -0.67945 0.3048)
			(end -0.120396 0.3048)
			(stroke
				(width 0.1)
				(type default)
			)
			(layer "B.Fab")
		)
		(fp_line
			(start -0.120396 0.3048)
			(end -0.120396 0.2794)
			(stroke
				(width 0.1)
				(type default)
			)
			(layer "B.Fab")
		)
		(fp_line
			(start 0.12065 0.3048)
			(end 0.67945 0.3048)
			(stroke
				(width 0.1)
				(type default)
			)
			(layer "B.Fab")
		)
		(fp_line
			(start 0.67945 0.3048)
			(end 0.67945 -0.305054)
			(stroke
				(width 0.1)
				(type default)
			)
			(layer "B.Fab")
		)
		(fp_line
			(start -0.120396 0.2794)
			(end 0.12065 0.2794)
			(stroke
				(width 0.1)
				(type default)
			)
			(layer "B.Fab")
		)
		(fp_line
			(start 0.12065 0.2794)
			(end 0.12065 0.3048)
			(stroke
				(width 0.1)
				(type default)
			)
			(layer "B.Fab")
		)
		(fp_line
			(start -0.12065 -0.2794)
			(end -0.12065 -0.3048)
			(stroke
				(width 0.1)
				(type default)
			)
			(layer "B.Fab")
		)
		(fp_line
			(start 0.12065 -0.2794)
			(end -0.12065 -0.2794)
			(stroke
				(width 0.1)
				(type default)
			)
			(layer "B.Fab")
		)
		(fp_line
			(start -0.67945 -0.3048)
			(end -0.67945 0.3048)
			(stroke
				(width 0.1)
				(type default)
			)
			(layer "B.Fab")
		)
		(fp_line
			(start -0.12065 -0.3048)
			(end -0.67945 -0.3048)
			(stroke
				(width 0.1)
				(type default)
			)
			(layer "B.Fab")
		)
		(fp_line
			(start 0.12065 -0.305054)
			(end 0.12065 -0.2794)
			(stroke
				(width 0.1)
				(type default)
			)
			(layer "B.Fab")
		)
		(fp_line
			(start 0.67945 -0.305054)
			(end 0.12065 -0.305054)
			(stroke
				(width 0.1)
				(type default)
			)
			(layer "B.Fab")
		)
		(pad "1" smd circle
			(at 0.40005 0 90)
			(size 0 0)
			(layers "B.Cu" "B.Mask" "B.Paste")
			(net "PWRGD_PLT_AUX_CPU0_LVT3_R")
		)
		(pad "2" smd circle
			(at -0.40005 0 90)
			(size 0 0)
			(layers "B.Cu" "B.Mask" "B.Paste")
			(net "PWRGD_PLT_AUX_CPU0_LVT3")
		)
	)
	(footprint ""
		(layer "B.Cu")
		(at 181.755542 -113.77549)
		(property "Reference" "C1146"
			(at 0 0 0)
			(layer "B.SilkS")
			(hide yes)
			(effects
				(font
					(size 1.27 1.27)
				)
				(justify mirror)
			)
		)
		(property "Value" ""
			(at 0 0 0)
			(layer "B.Fab")
			(effects
				(font
					(size 1.27 1.27)
				)
				(justify mirror)
			)
		)
		(duplicate_pad_numbers_are_jumpers no)
		(fp_line
			(start -0.69215 -0.2921)
			(end -0.69215 0.2921)
			(stroke
				(width 0.1524)
				(type default)
			)
			(layer "B.SilkS")
		)
		(fp_line
			(start -0.69215 0.2921)
			(end 0.69215 0.2921)
			(stroke
				(width 0.1524)
				(type default)
			)
			(layer "B.SilkS")
		)
		(fp_line
			(start 0.69215 -0.2921)
			(end -0.69215 -0.2921)
			(stroke
				(width 0.1524)
				(type default)
			)
			(layer "B.SilkS")
		)
		(fp_line
			(start 0.69215 0.2921)
			(end 0.69215 -0.2921)
			(stroke
				(width 0.1524)
				(type default)
			)
			(layer "B.SilkS")
		)
		(fp_line
			(start -0.51435 -0.2794)
			(end -0.51435 0.2794)
			(stroke
				(width 0.1)
				(type default)
			)
			(layer "B.Fab")
		)
		(fp_line
			(start -0.51435 0.2794)
			(end 0.51435 0.2794)
			(stroke
				(width 0.1)
				(type default)
			)
			(layer "B.Fab")
		)
		(fp_line
			(start 0.51435 -0.2794)
			(end -0.51435 -0.2794)
			(stroke
				(width 0.1)
				(type default)
			)
			(layer "B.Fab")
		)
		(fp_line
			(start 0.51435 0.2794)
			(end 0.51435 -0.2794)
			(stroke
				(width 0.1)
				(type default)
			)
			(layer "B.Fab")
		)
		(pad "1" smd circle
			(at 0.40005 0 180)
			(size 0 0)
			(layers "B.Cu" "B.Mask" "B.Paste")
			(net "P3V3_AUX_FPGA_VCCIO2")
		)
		(pad "2" smd circle
			(at -0.40005 0 180)
			(size 0 0)
			(layers "B.Cu" "B.Mask" "B.Paste")
			(net "GND")
		)
		(zone
			(layer "B.Cu")
			(hatch none 0.5)
			(connect_pads
				(clearance 0)
			)
			(min_thickness 0.25)
			(keepout
				(tracks not_allowed)
				(vias allowed)
				(pads allowed)
				(copperpour not_allowed)
				(footprints allowed)
			)
			(placement
				(enabled no)
				(sheetname "")
			)
			(fill
				(thermal_gap 0.5)
				(thermal_bridge_width 0.5)
				(island_removal_mode 0)
			)
			(polygon
				(pts
					(xy 181.946042 -113.68786) (xy 181.854602 -113.629694) (xy 181.655212 -113.629694) (xy 181.565042 -113.68786)
					(xy 181.565042 -113.86312) (xy 181.655212 -113.92154) (xy 181.854602 -113.92154) (xy 181.946042 -113.863374)
				)
			)
		)
	)
	(footprint ""
		(layer "B.Cu")
		(at 191.264286 -193.615056 -90)
		(property "Reference" "C613"
			(at 0 0 90)
			(layer "B.SilkS")
			(hide yes)
			(effects
				(font
					(size 1.27 1.27)
				)
				(justify mirror)
			)
		)
		(property "Value" ""
			(at 0 0 90)
			(layer "B.Fab")
			(effects
				(font
					(size 1.27 1.27)
				)
				(justify mirror)
			)
		)
		(duplicate_pad_numbers_are_jumpers no)
		(fp_line
			(start -0.7874 0.4064)
			(end 0.7874 0.4064)
			(stroke
				(width 0.1524)
				(type default)
			)
			(layer "B.SilkS")
		)
		(fp_line
			(start 0.7874 0.4064)
			(end 0.7874 -0.4064)
			(stroke
				(width 0.1524)
				(type default)
			)
			(layer "B.SilkS")
		)
		(fp_line
			(start -0.7874 -0.4064)
			(end -0.7874 0.4064)
			(stroke
				(width 0.1524)
				(type default)
			)
			(layer "B.SilkS")
		)
		(fp_line
			(start 0.7874 -0.4064)
			(end -0.7874 -0.4064)
			(stroke
				(width 0.1524)
				(type default)
			)
			(layer "B.SilkS")
		)
		(fp_line
			(start -0.67945 0.3048)
			(end -0.120396 0.3048)
			(stroke
				(width 0.1)
				(type default)
			)
			(layer "B.Fab")
		)
		(fp_line
			(start -0.120396 0.3048)
			(end -0.120396 0.2794)
			(stroke
				(width 0.1)
				(type default)
			)
			(layer "B.Fab")
		)
		(fp_line
			(start 0.12065 0.3048)
			(end 0.67945 0.3048)
			(stroke
				(width 0.1)
				(type default)
			)
			(layer "B.Fab")
		)
		(fp_line
			(start 0.67945 0.3048)
			(end 0.67945 -0.305054)
			(stroke
				(width 0.1)
				(type default)
			)
			(layer "B.Fab")
		)
		(fp_line
			(start -0.120396 0.2794)
			(end 0.12065 0.2794)
			(stroke
				(width 0.1)
				(type default)
			)
			(layer "B.Fab")
		)
		(fp_line
			(start 0.12065 0.2794)
			(end 0.12065 0.3048)
			(stroke
				(width 0.1)
				(type default)
			)
			(layer "B.Fab")
		)
		(fp_line
			(start -0.12065 -0.2794)
			(end -0.12065 -0.3048)
			(stroke
				(width 0.1)
				(type default)
			)
			(layer "B.Fab")
		)
		(fp_line
			(start 0.12065 -0.2794)
			(end -0.12065 -0.2794)
			(stroke
				(width 0.1)
				(type default)
			)
			(layer "B.Fab")
		)
		(fp_line
			(start -0.67945 -0.3048)
			(end -0.67945 0.3048)
			(stroke
				(width 0.1)
				(type default)
			)
			(layer "B.Fab")
		)
		(fp_line
			(start -0.12065 -0.3048)
			(end -0.67945 -0.3048)
			(stroke
				(width 0.1)
				(type default)
			)
			(layer "B.Fab")
		)
		(fp_line
			(start 0.12065 -0.305054)
			(end 0.12065 -0.2794)
			(stroke
				(width 0.1)
				(type default)
			)
			(layer "B.Fab")
		)
		(fp_line
			(start 0.67945 -0.305054)
			(end 0.12065 -0.305054)
			(stroke
				(width 0.1)
				(type default)
			)
			(layer "B.Fab")
		)
		(pad "1" smd circle
			(at 0.40005 0 90)
			(size 0 0)
			(layers "B.Cu" "B.Mask" "B.Paste")
			(net "RST_PLD_CPU1_DRAM_GH_N")
		)
		(pad "2" smd circle
			(at -0.40005 0 90)
			(size 0 0)
			(layers "B.Cu" "B.Mask" "B.Paste")
			(net "GND")
		)
	)
	(footprint ""
		(layer "B.Cu")
		(at 366.992408 -325.110094 -90)
		(property "Reference" "PC308_P0_1"
			(at 0 0 90)
			(layer "B.SilkS")
			(hide yes)
			(effects
				(font
					(size 1.27 1.27)
				)
				(justify mirror)
			)
		)
		(property "Value" ""
			(at 0 0 90)
			(layer "B.Fab")
			(effects
				(font
					(size 1.27 1.27)
				)
				(justify mirror)
			)
		)
		(duplicate_pad_numbers_are_jumpers no)
		(fp_line
			(start -0.7874 0.4064)
			(end 0.7874 0.4064)
			(stroke
				(width 0.1524)
				(type default)
			)
			(layer "B.SilkS")
		)
		(fp_line
			(start 0.7874 0.4064)
			(end 0.7874 -0.4064)
			(stroke
				(width 0.1524)
				(type default)
			)
			(layer "B.SilkS")
		)
		(fp_line
			(start -0.7874 -0.4064)
			(end -0.7874 0.4064)
			(stroke
				(width 0.1524)
				(type default)
			)
			(layer "B.SilkS")
		)
		(fp_line
			(start 0.7874 -0.4064)
			(end -0.7874 -0.4064)
			(stroke
				(width 0.1524)
				(type default)
			)
			(layer "B.SilkS")
		)
		(fp_line
			(start -0.67945 0.3048)
			(end -0.120396 0.3048)
			(stroke
				(width 0.1)
				(type default)
			)
			(layer "B.Fab")
		)
		(fp_line
			(start -0.120396 0.3048)
			(end -0.120396 0.2794)
			(stroke
				(width 0.1)
				(type default)
			)
			(layer "B.Fab")
		)
		(fp_line
			(start 0.12065 0.3048)
			(end 0.67945 0.3048)
			(stroke
				(width 0.1)
				(type default)
			)
			(layer "B.Fab")
		)
		(fp_line
			(start 0.67945 0.3048)
			(end 0.67945 -0.305054)
			(stroke
				(width 0.1)
				(type default)
			)
			(layer "B.Fab")
		)
		(fp_line
			(start -0.120396 0.2794)
			(end 0.12065 0.2794)
			(stroke
				(width 0.1)
				(type default)
			)
			(layer "B.Fab")
		)
		(fp_line
			(start 0.12065 0.2794)
			(end 0.12065 0.3048)
			(stroke
				(width 0.1)
				(type default)
			)
			(layer "B.Fab")
		)
		(fp_line
			(start -0.12065 -0.2794)
			(end -0.12065 -0.3048)
			(stroke
				(width 0.1)
				(type default)
			)
			(layer "B.Fab")
		)
		(fp_line
			(start 0.12065 -0.2794)
			(end -0.12065 -0.2794)
			(stroke
				(width 0.1)
				(type default)
			)
			(layer "B.Fab")
		)
		(fp_line
			(start -0.67945 -0.3048)
			(end -0.67945 0.3048)
			(stroke
				(width 0.1)
				(type default)
			)
			(layer "B.Fab")
		)
		(fp_line
			(start -0.12065 -0.3048)
			(end -0.67945 -0.3048)
			(stroke
				(width 0.1)
				(type default)
			)
			(layer "B.Fab")
		)
		(fp_line
			(start 0.12065 -0.305054)
			(end 0.12065 -0.2794)
			(stroke
				(width 0.1)
				(type default)
			)
			(layer "B.Fab")
		)
		(fp_line
			(start 0.67945 -0.305054)
			(end 0.12065 -0.305054)
			(stroke
				(width 0.1)
				(type default)
			)
			(layer "B.Fab")
		)
		(pad "1" smd circle
			(at 0.40005 0 90)
			(size 0 0)
			(layers "B.Cu" "B.Mask" "B.Paste")
			(net "PVCCIN_CPU0")
		)
		(pad "2" smd circle
			(at -0.40005 0 90)
			(size 0 0)
			(layers "B.Cu" "B.Mask" "B.Paste")
			(net "GND")
		)
	)
	(footprint ""
		(layer "B.Cu")
		(at 331.146912 -32.71266 90)
		(property "Reference" "R375"
			(at 0 0 90)
			(layer "B.SilkS")
			(hide yes)
			(effects
				(font
					(size 1.27 1.27)
				)
				(justify mirror)
			)
		)
		(property "Value" ""
			(at 0 0 90)
			(layer "B.Fab")
			(effects
				(font
					(size 1.27 1.27)
				)
				(justify mirror)
			)
		)
		(duplicate_pad_numbers_are_jumpers no)
		(fp_line
			(start 0.7874 -0.4064)
			(end -0.7874 -0.4064)
			(stroke
				(width 0.1524)
				(type default)
			)
			(layer "B.SilkS")
		)
		(fp_line
			(start -0.7874 -0.4064)
			(end -0.7874 0.4064)
			(stroke
				(width 0.1524)
				(type default)
			)
			(layer "B.SilkS")
		)
		(fp_line
			(start 0.7874 0.4064)
			(end 0.7874 -0.4064)
			(stroke
				(width 0.1524)
				(type default)
			)
			(layer "B.SilkS")
		)
		(fp_line
			(start -0.7874 0.4064)
			(end 0.7874 0.4064)
			(stroke
				(width 0.1524)
				(type default)
			)
			(layer "B.SilkS")
		)
		(fp_line
			(start 0.67945 -0.305054)
			(end 0.12065 -0.305054)
			(stroke
				(width 0.1)
				(type default)
			)
			(layer "B.Fab")
		)
		(fp_line
			(start 0.12065 -0.305054)
			(end 0.12065 -0.2794)
			(stroke
				(width 0.1)
				(type default)
			)
			(layer "B.Fab")
		)
		(fp_line
			(start -0.12065 -0.3048)
			(end -0.67945 -0.3048)
			(stroke
				(width 0.1)
				(type default)
			)
			(layer "B.Fab")
		)
		(fp_line
			(start -0.67945 -0.3048)
			(end -0.67945 0.3048)
			(stroke
				(width 0.1)
				(type default)
			)
			(layer "B.Fab")
		)
		(fp_line
			(start 0.12065 -0.2794)
			(end -0.12065 -0.2794)
			(stroke
				(width 0.1)
				(type default)
			)
			(layer "B.Fab")
		)
		(fp_line
			(start -0.12065 -0.2794)
			(end -0.12065 -0.3048)
			(stroke
				(width 0.1)
				(type default)
			)
			(layer "B.Fab")
		)
		(fp_line
			(start 0.12065 0.2794)
			(end 0.12065 0.3048)
			(stroke
				(width 0.1)
				(type default)
			)
			(layer "B.Fab")
		)
		(fp_line
			(start -0.120396 0.2794)
			(end 0.12065 0.2794)
			(stroke
				(width 0.1)
				(type default)
			)
			(layer "B.Fab")
		)
		(fp_line
			(start 0.67945 0.3048)
			(end 0.67945 -0.305054)
			(stroke
				(width 0.1)
				(type default)
			)
			(layer "B.Fab")
		)
		(fp_line
			(start 0.12065 0.3048)
			(end 0.67945 0.3048)
			(stroke
				(width 0.1)
				(type default)
			)
			(layer "B.Fab")
		)
		(fp_line
			(start -0.120396 0.3048)
			(end -0.120396 0.2794)
			(stroke
				(width 0.1)
				(type default)
			)
			(layer "B.Fab")
		)
		(fp_line
			(start -0.67945 0.3048)
			(end -0.120396 0.3048)
			(stroke
				(width 0.1)
				(type default)
			)
			(layer "B.Fab")
		)
		(pad "1" smd circle
			(at 0.40005 0 270)
			(size 0 0)
			(layers "B.Cu" "B.Mask" "B.Paste")
			(net "FM_SPI_3V3_1V8_VOLTAGE")
		)
		(pad "2" smd circle
			(at -0.40005 0 270)
			(size 0 0)
			(layers "B.Cu" "B.Mask" "B.Paste")
			(net "GND")
		)
	)
	(footprint ""
		(layer "B.Cu")
		(at 152.339802 -190.359284 -90)
		(property "Reference" "R669"
			(at 0 0 90)
			(layer "B.SilkS")
			(hide yes)
			(effects
				(font
					(size 1.27 1.27)
				)
				(justify mirror)
			)
		)
		(property "Value" ""
			(at 0 0 90)
			(layer "B.Fab")
			(effects
				(font
					(size 1.27 1.27)
				)
				(justify mirror)
			)
		)
		(duplicate_pad_numbers_are_jumpers no)
		(fp_line
			(start -0.7874 0.4064)
			(end 0.7874 0.4064)
			(stroke
				(width 0.1524)
				(type default)
			)
			(layer "B.SilkS")
		)
		(fp_line
			(start 0.7874 0.4064)
			(end 0.7874 -0.4064)
			(stroke
				(width 0.1524)
				(type default)
			)
			(layer "B.SilkS")
		)
		(fp_line
			(start -0.7874 -0.4064)
			(end -0.7874 0.4064)
			(stroke
				(width 0.1524)
				(type default)
			)
			(layer "B.SilkS")
		)
		(fp_line
			(start 0.7874 -0.4064)
			(end -0.7874 -0.4064)
			(stroke
				(width 0.1524)
				(type default)
			)
			(layer "B.SilkS")
		)
		(fp_line
			(start -0.67945 0.3048)
			(end -0.120396 0.3048)
			(stroke
				(width 0.1)
				(type default)
			)
			(layer "B.Fab")
		)
		(fp_line
			(start -0.120396 0.3048)
			(end -0.120396 0.2794)
			(stroke
				(width 0.1)
				(type default)
			)
			(layer "B.Fab")
		)
		(fp_line
			(start 0.12065 0.3048)
			(end 0.67945 0.3048)
			(stroke
				(width 0.1)
				(type default)
			)
			(layer "B.Fab")
		)
		(fp_line
			(start 0.67945 0.3048)
			(end 0.67945 -0.305054)
			(stroke
				(width 0.1)
				(type default)
			)
			(layer "B.Fab")
		)
		(fp_line
			(start -0.120396 0.2794)
			(end 0.12065 0.2794)
			(stroke
				(width 0.1)
				(type default)
			)
			(layer "B.Fab")
		)
		(fp_line
			(start 0.12065 0.2794)
			(end 0.12065 0.3048)
			(stroke
				(width 0.1)
				(type default)
			)
			(layer "B.Fab")
		)
		(fp_line
			(start -0.12065 -0.2794)
			(end -0.12065 -0.3048)
			(stroke
				(width 0.1)
				(type default)
			)
			(layer "B.Fab")
		)
		(fp_line
			(start 0.12065 -0.2794)
			(end -0.12065 -0.2794)
			(stroke
				(width 0.1)
				(type default)
			)
			(layer "B.Fab")
		)
		(fp_line
			(start -0.67945 -0.3048)
			(end -0.67945 0.3048)
			(stroke
				(width 0.1)
				(type default)
			)
			(layer "B.Fab")
		)
		(fp_line
			(start -0.12065 -0.3048)
			(end -0.67945 -0.3048)
			(stroke
				(width 0.1)
				(type default)
			)
			(layer "B.Fab")
		)
		(fp_line
			(start 0.12065 -0.305054)
			(end 0.12065 -0.2794)
			(stroke
				(width 0.1)
				(type default)
			)
			(layer "B.Fab")
		)
		(fp_line
			(start 0.67945 -0.305054)
			(end 0.12065 -0.305054)
			(stroke
				(width 0.1)
				(type default)
			)
			(layer "B.Fab")
		)
		(pad "1" smd circle
			(at 0.40005 0 90)
			(size 0 0)
			(layers "B.Cu" "B.Mask" "B.Paste")
			(net "PVNN_TERM_CPU1")
		)
		(pad "2" smd circle
			(at -0.40005 0 90)
			(size 0 0)
			(layers "B.Cu" "B.Mask" "B.Paste")
			(net "I3C_SPD_DDREFGH_CPU1_SDA")
		)
	)
)
